# BASEBOARD_FAB2 (Tioga Pass) — schematic netlist excerpt (pin names and nets, part order shuffled) for the footprints in the layout excerpt that follows; sources: Cadence DE-HDL packaged netlist, KiCad conversion of Wiwynn_Tioga_Pass_MB.brd

EU4D4  PXE1610B  IC  pkg QFN  page 201
  BPWM1  = VR_PVSA_CPU0_PWM
  APWM6  = NC
  APWM5  = VR_PVCCIN_CPU0_PWM5
  APWM4  = VR_PVCCIN_CPU0_PWM4
  APWM3  = VR_PVCCIN_CPU0_PWM3
  APWM2  = VR_PVCCIN_CPU0_PWM2
  APWM1  = VR_PVCCIN_CPU0_PWM1
  SDA  = SMB_VR_STBY_LVC3_SDA
  SCL  = SMB_VR_STBY_LVC3_SCL
  RESET_N  = NC
  AVRRDY  = VR_VRRDY_PVCCIN_CPU0
  AVREN  = VR_PVCCIN_CPU0_VREN
  VRHOT_N  = IRQ_PVCCIN_CPU0_VRHOT_LVC3_R_N
  PINALRT_N  = FM_PVCCIN_CPU0_PWR_IN_ALERT_N
  MP0  = PWRGD_PVSA_CPU0_R
  MP1  = NC
  VCLK  = SVID_VCLK_PVCCIN_CPU0
  VDIO  = SVID_VDIO_PVCCIN_CPU0
  VALRT_N  = SVID_VALERT_VCCIN_CPU0
  MP2  = PU_VR_PVCCIN_CPU0_FLT1_SMBALT_N
  AVSEN  = VSENSE_PVCCIN_CPU0_AVSP
  AVREF  = VSENSE_PVCCIN_CPU0_N
  AIREF1  = VR_PVCCIN_CPU0_AIREF1
  AISEN1  = ISENSE_PVCCIN_CPU0_PH1_IMON
  AIREF2  = VR_PVCCIN_CPU0_AIREF2
  AISEN2  = ISENSE_PVCCIN_CPU0_PH2_IMON
  AIREF3  = VR_PVCCIN_CPU0_AIREF3
  AISEN3  = ISENSE_PVCCIN_CPU0_PH3_IMON
  AIREF4  = VR_PVCCIN_CPU0_AIREF4
  AISEN4  = ISENSE_PVCCIN_CPU0_PH4_IMON
  AIREF5  = VR_PVCCIN_CPU0_AIREF5
  AISEN5  = ISENSE_PVCCIN_CPU0_PH5_IMON
  AIREF6  = NC
  AISEN6  = NC
  BVSEN  = VSENSE_PVSA_CPU0_BVSP
  BVREF  = VSENSE_PVSA_CPU0_N
  BIREF1  = VR_PVSA_CPU0_BIREF1
  BISEN1  = ISENSE_PVSA_CPU0_IMON
  MP3  = PU_VR_PVCCIN_CPU0_IMON
  MP4  = NC
  XADDR2  = VR_PVCCIN_CPU0_XADDR2
  BTSEN  = A_TSENSE_PVSA_CPU0
  ATSEN  = A_TSENSE_PVCCIN_CPU0
  XADDR1  = VR_PVCCIN_CPU0_XADDR1
  VINSEN  = VR_PVCCIN_CPU0_AVINSEN
  IINSEN  = NC
  VDD  = VR_PVCCIN_CPU0_VDD
  VD12  = VR_PVCCIN_CPU0_VD12
  THPAD  = GND

(kicad_pcb
	(version 20260206)
	(generator "pcbnew")
	(generator_version "10.0")
	(general
		(thickness 1.6)
		(legacy_teardrops no)
	)
	(paper "A4")
	(title_block
		(title "Wiwynn_Tioga_Pass_MB.brd")
		(comment 1 "Tioga Pass / footprint 1893 of 4770 (EU4D4), pads 35-49 of 49")
	)
	(layers
		(0 "F.Cu" signal "TOP")
		(4 "In1.Cu" signal "L2GND")
		(6 "In2.Cu" signal "L3")
		(8 "In3.Cu" signal "L4GND")
		(10 "In4.Cu" signal "L5")
		(12 "In5.Cu" signal "L6GND")
		(14 "In6.Cu" signal "L7VCC")
		(16 "In7.Cu" signal "L8VCC")
		(18 "In8.Cu" signal "L9GND")
		(20 "In9.Cu" signal "L10")
		(22 "In10.Cu" signal "L11GND")
		(24 "In11.Cu" signal "L12")
		(26 "In12.Cu" signal "L13GND")
		(2 "B.Cu" signal "BOTTOM")
		(9 "F.Adhes" user "F.Adhesive")
		(11 "B.Adhes" user "B.Adhesive")
		(13 "F.Paste" user "Package Geometry/Pastemask Top")
		(15 "B.Paste" user "Package Geometry/Pastemask Bottom")
		(5 "F.SilkS" user "Ref Des/Silkscreen Top")
		(7 "B.SilkS" user "Ref Des/Silkscreen Bottom")
		(1 "F.Mask" user "Board Geometry/Soldermask Top")
		(3 "B.Mask" user "Board Geometry/Soldermask Bottom")
		(17 "Dwgs.User" user "User.Drawings")
		(19 "Cmts.User" user "User.Comments")
		(21 "Eco1.User" user "User.Eco1")
		(23 "Eco2.User" user "User.Eco2")
		(25 "Edge.Cuts" user "Board Geometry/Outline")
		(27 "Margin" user)
		(31 "F.CrtYd" user "Package Geometry/Place Bound Top")
		(29 "B.CrtYd" user "Package Geometry/Place Bound Bottom")
		(35 "F.Fab" user "Ref Des/Assembly Top")
		(33 "B.Fab" user "Ref Des/Assembly Bottom")
	)
	(footprint ""
		(layer "F.Cu")
		(at 184.277 -69.85)
		(property "Reference" "EU4D4"
			(at -7.4422 -3.32613 0)
			(unlocked yes)
			(layer "F.SilkS")
			(effects
				(font
					(size 0.7874 0.5842)
					(thickness 0.1524)
				)
				(justify left)
			)
		)
		(property "Value" ""
			(at 0 0 0)
			(layer "F.Fab")
			(effects
				(font
					(size 1.27 1.27)
				)
			)
		)
		(duplicate_pad_numbers_are_jumpers no)
		(pad "35" smd custom
			(at 2.8956 -1.800098)
			(size 0.0508 0.0508)
			(layers "F.Cu" "F.Mask" "F.Paste")
			(net "VSENSE_PVSA_CPU0_BVSP")
			(options
				(clearance outline)
				(anchor circle)
			)
			(primitives
				(gr_poly
					(pts
						(arc
							(start -0.254 0.1016)
							(mid -0.3556 0)
							(end -0.254 -0.1016)
						)
						(xy 0.3556 -0.1016) (xy 0.3556 0.1016)
					)
					(width 0)
					(fill yes)
				)
			)
		)
		(pad "36" smd custom
			(at 2.8956 -2.199894)
			(size 0.0508 0.0508)
			(layers "F.Cu" "F.Mask" "F.Paste")
			(net "VSENSE_PVSA_CPU0_N")
			(options
				(clearance outline)
				(anchor circle)
			)
			(primitives
				(gr_poly
					(pts
						(arc
							(start -0.254 0.1016)
							(mid -0.3556 0)
							(end -0.254 -0.1016)
						)
						(xy 0.3556 -0.1016) (xy 0.3556 0.1016)
					)
					(width 0)
					(fill yes)
				)
			)
		)
		(pad "37" smd custom
			(at 2.199894 -2.8956)
			(size 0.0508 0.0508)
			(layers "F.Cu" "F.Mask" "F.Paste")
			(net "VR_PVSA_CPU0_BIREF1")
			(options
				(clearance outline)
				(anchor circle)
			)
			(primitives
				(gr_poly
					(pts
						(arc
							(start 0.1016 0.254)
							(mid 0 0.3556)
							(end -0.1016 0.254)
						)
						(xy -0.1016 -0.3556) (xy 0.1016 -0.3556)
					)
					(width 0)
					(fill yes)
				)
			)
		)
		(pad "38" smd custom
			(at 1.800098 -2.8956)
			(size 0.0508 0.0508)
			(layers "F.Cu" "F.Mask" "F.Paste")
			(net "ISENSE_PVSA_CPU0_IMON")
			(options
				(clearance outline)
				(anchor circle)
			)
			(primitives
				(gr_poly
					(pts
						(arc
							(start 0.1016 0.254)
							(mid 0 0.3556)
							(end -0.1016 0.254)
						)
						(xy -0.1016 -0.3556) (xy 0.1016 -0.3556)
					)
					(width 0)
					(fill yes)
				)
			)
		)
		(pad "39" smd custom
			(at 1.400048 -2.8956)
			(size 0.0508 0.0508)
			(layers "F.Cu" "F.Mask" "F.Paste")
			(net "PU_VR_PVCCIN_CPU0_IMON")
			(options
				(clearance outline)
				(anchor circle)
			)
			(primitives
				(gr_poly
					(pts
						(arc
							(start 0.1016 0.254)
							(mid 0 0.3556)
							(end -0.1016 0.254)
						)
						(xy -0.1016 -0.3556) (xy 0.1016 -0.3556)
					)
					(width 0)
					(fill yes)
				)
			)
		)
		(pad "40" smd custom
			(at 0.999998 -2.8956)
			(size 0.0508 0.0508)
			(layers "F.Cu" "F.Mask" "F.Paste")
			(net "Net_292")
			(options
				(clearance outline)
				(anchor circle)
			)
			(primitives
				(gr_poly
					(pts
						(arc
							(start 0.1016 0.254)
							(mid 0 0.3556)
							(end -0.1016 0.254)
						)
						(xy -0.1016 -0.3556) (xy 0.1016 -0.3556)
					)
					(width 0)
					(fill yes)
				)
			)
		)
		(pad "41" smd custom
			(at 0.599948 -2.8956)
			(size 0.0508 0.0508)
			(layers "F.Cu" "F.Mask" "F.Paste")
			(net "VR_PVCCIN_CPU0_XADDR2")
			(options
				(clearance outline)
				(anchor circle)
			)
			(primitives
				(gr_poly
					(pts
						(arc
							(start 0.1016 0.254)
							(mid 0 0.3556)
							(end -0.1016 0.254)
						)
						(xy -0.1016 -0.3556) (xy 0.1016 -0.3556)
					)
					(width 0)
					(fill yes)
				)
			)
		)
		(pad "42" smd custom
			(at 0.199898 -2.8956)
			(size 0.0508 0.0508)
			(layers "F.Cu" "F.Mask" "F.Paste")
			(net "A_TSENSE_PVSA_CPU0")
			(options
				(clearance outline)
				(anchor circle)
			)
			(primitives
				(gr_poly
					(pts
						(arc
							(start 0.1016 0.254)
							(mid 0 0.3556)
							(end -0.1016 0.254)
						)
						(xy -0.1016 -0.3556) (xy 0.1016 -0.3556)
					)
					(width 0)
					(fill yes)
				)
			)
		)
		(pad "43" smd custom
			(at -0.199898 -2.8956)
			(size 0.0508 0.0508)
			(layers "F.Cu" "F.Mask" "F.Paste")
			(net "A_TSENSE_PVCCIN_CPU0")
			(options
				(clearance outline)
				(anchor circle)
			)
			(primitives
				(gr_poly
					(pts
						(arc
							(start 0.1016 0.254)
							(mid 0 0.3556)
							(end -0.1016 0.254)
						)
						(xy -0.1016 -0.3556) (xy 0.1016 -0.3556)
					)
					(width 0)
					(fill yes)
				)
			)
		)
		(pad "44" smd custom
			(at -0.599948 -2.8956)
			(size 0.0508 0.0508)
			(layers "F.Cu" "F.Mask" "F.Paste")
			(net "VR_PVCCIN_CPU0_XADDR1")
			(options
				(clearance outline)
				(anchor circle)
			)
			(primitives
				(gr_poly
					(pts
						(arc
							(start 0.1016 0.254)
							(mid 0 0.3556)
							(end -0.1016 0.254)
						)
						(xy -0.1016 -0.3556) (xy 0.1016 -0.3556)
					)
					(width 0)
					(fill yes)
				)
			)
		)
		(pad "45" smd custom
			(at -0.999998 -2.8956)
			(size 0.0508 0.0508)
			(layers "F.Cu" "F.Mask" "F.Paste")
			(net "VR_PVCCIN_CPU0_AVINSEN")
			(options
				(clearance outline)
				(anchor circle)
			)
			(primitives
				(gr_poly
					(pts
						(arc
							(start 0.1016 0.254)
							(mid 0 0.3556)
							(end -0.1016 0.254)
						)
						(xy -0.1016 -0.3556) (xy 0.1016 -0.3556)
					)
					(width 0)
					(fill yes)
				)
			)
		)
		(pad "46" smd custom
			(at -1.400048 -2.8956)
			(size 0.0508 0.0508)
			(layers "F.Cu" "F.Mask" "F.Paste")
			(net "Net_217")
			(options
				(clearance outline)
				(anchor circle)
			)
			(primitives
				(gr_poly
					(pts
						(arc
							(start 0.1016 0.254)
							(mid 0 0.3556)
							(end -0.1016 0.254)
						)
						(xy -0.1016 -0.3556) (xy 0.1016 -0.3556)
					)
					(width 0)
					(fill yes)
				)
			)
		)
		(pad "47" smd custom
			(at -1.800098 -2.8956)
			(size 0.0508 0.0508)
			(layers "F.Cu" "F.Mask" "F.Paste")
			(net "VR_PVCCIN_CPU0_VDD")
			(options
				(clearance outline)
				(anchor circle)
			)
			(primitives
				(gr_poly
					(pts
						(arc
							(start 0.1016 0.254)
							(mid 0 0.3556)
							(end -0.1016 0.254)
						)
						(xy -0.1016 -0.3556) (xy 0.1016 -0.3556)
					)
					(width 0)
					(fill yes)
				)
			)
		)
		(pad "48" smd custom
			(at -2.199894 -2.8956)
			(size 0.0508 0.0508)
			(layers "F.Cu" "F.Mask" "F.Paste")
			(net "VR_PVCCIN_CPU0_VD12")
			(options
				(clearance outline)
				(anchor circle)
			)
			(primitives
				(gr_poly
					(pts
						(arc
							(start 0.1016 0.254)
							(mid 0 0.3556)
							(end -0.1016 0.254)
						)
						(xy -0.1016 -0.3556) (xy 0.1016 -0.3556)
					)
					(width 0)
					(fill yes)
				)
			)
		)
		(pad "49" smd rect
			(at 0 0)
			(size 3.6068 3.6068)
			(layers "F.Cu" "F.Mask" "F.Paste")
			(net "GND")
		)
	)
)
